(kicad_pcb
	(version 20260206)
	(generator "pcbnew")
	(generator_version "10.0")
	(general
		(thickness 1.6)
		(legacy_teardrops no)
	)
	(paper "A4")
	(title_block
		(title "Bryce Canyon_IOM_IOC_16318-2_OCP.brd")
		(comment 1 "Bryce Canyon / footprints 1155-1161 of 1605")
	)
	(layers
		(0 "F.Cu" signal "TOP")
		(4 "In1.Cu" signal "L2GND")
		(6 "In2.Cu" signal "L3")
		(8 "In3.Cu" signal "L4VCC")
		(10 "In4.Cu" signal "L5VCC")
		(12 "In5.Cu" signal "L6")
		(14 "In6.Cu" signal "L7GND")
		(2 "B.Cu" signal "BOTTOM")
		(9 "F.Adhes" user "F.Adhesive")
		(11 "B.Adhes" user "B.Adhesive")
		(13 "F.Paste" user "Package Geometry/Pastemask Top")
		(15 "B.Paste" user "Package Geometry/Pastemask Bottom")
		(5 "F.SilkS" user "Ref Des/Silkscreen Top")
		(7 "B.SilkS" user "Ref Des/Silkscreen Bottom")
		(1 "F.Mask" user "Board Geometry/Soldermask Top")
		(3 "B.Mask" user "Board Geometry/Soldermask Bottom")
		(17 "Dwgs.User" user "User.Drawings")
		(19 "Cmts.User" user "User.Comments")
		(21 "Eco1.User" user "User.Eco1")
		(23 "Eco2.User" user "User.Eco2")
		(25 "Edge.Cuts" user "Board Geometry/Outline")
		(27 "Margin" user)
		(31 "F.CrtYd" user "Package Geometry/Place Bound Top")
		(29 "B.CrtYd" user "Package Geometry/Place Bound Bottom")
		(35 "F.Fab" user "Ref Des/Assembly Top")
		(33 "B.Fab" user "Ref Des/Assembly Bottom")
	)
	(footprint ""
		(layer "B.Cu")
		(at 25.343104 -142.282164 -90)
		(property "Reference" "R222"
			(at 0 0 90)
			(layer "B.SilkS")
			(hide yes)
			(effects
				(font
					(size 1.27 1.27)
				)
				(justify mirror)
			)
		)
		(property "Value" "120R2F-GP"
			(at -0.064008 -3.993896 270)
			(unlocked yes)
			(layer "B.Fab")
			(hide yes)
			(effects
				(font
					(size 1.016 1.016)
					(thickness 0.1524)
				)
				(justify mirror)
			)
		)
		(property "Device Type" "R402H16"
			(at -0.064008 -5.517896 270)
			(unlocked yes)
			(layer "B.Fab")
			(hide yes)
			(effects
				(font
					(size 1.016 1.016)
					(thickness 0.1524)
				)
				(justify mirror)
			)
		)
		(duplicate_pad_numbers_are_jumpers no)
		(fp_line
			(start -0.508 -0.9398)
			(end 0.508 -0.9398)
			(stroke
				(width 0.1524)
				(type default)
			)
			(layer "B.SilkS")
		)
		(fp_line
			(start 0.508 -0.9398)
			(end 0.508 0.9398)
			(stroke
				(width 0.1524)
				(type default)
			)
			(layer "B.SilkS")
		)
		(fp_rect
			(start 0.508 0.9398)
			(end -0.508 -0.9398)
			(stroke
				(width 0)
				(type default)
			)
			(fill no)
			(layer "B.CrtYd")
		)
		(fp_rect
			(start 0.508 0.9398)
			(end -0.508 -0.9398)
			(stroke
				(width 0)
				(type default)
			)
			(fill no)
			(layer "B.Fab")
		)
		(pad "1" smd custom
			(at 0 -0.4445 90)
			(size 0.1397 0.1397)
			(layers "B.Cu" "B.Mask" "B.Paste")
			(net "GND")
			(options
				(clearance outline)
				(anchor circle)
			)
			(primitives
				(gr_poly
					(pts
						(arc
							(start -0.1778 0.2794)
							(mid -0.249642 0.249642)
							(end -0.2794 0.1778)
						)
						(arc
							(start -0.2794 -0.1778)
							(mid -0.249642 -0.249642)
							(end -0.1778 -0.2794)
						)
						(arc
							(start 0.1778 -0.2794)
							(mid 0.249642 -0.249642)
							(end 0.2794 -0.1778)
						)
						(arc
							(start 0.2794 0.1778)
							(mid 0.249642 0.249642)
							(end 0.1778 0.2794)
						)
					)
					(width 0)
					(fill yes)
				)
			)
		)
		(pad "2" smd custom
			(at 0 0.4445 90)
			(size 0.1397 0.1397)
			(layers "B.Cu" "B.Mask" "B.Paste")
			(net "MEMRASN")
			(options
				(clearance outline)
				(anchor circle)
			)
			(primitives
				(gr_poly
					(pts
						(arc
							(start -0.1778 0.2794)
							(mid -0.249642 0.249642)
							(end -0.2794 0.1778)
						)
						(arc
							(start -0.2794 -0.1778)
							(mid -0.249642 -0.249642)
							(end -0.1778 -0.2794)
						)
						(arc
							(start 0.1778 -0.2794)
							(mid 0.249642 -0.249642)
							(end 0.2794 -0.1778)
						)
						(arc
							(start 0.2794 0.1778)
							(mid 0.249642 0.249642)
							(end 0.1778 0.2794)
						)
					)
					(width 0)
					(fill yes)
				)
			)
		)
	)
	(footprint ""
		(layer "B.Cu")
		(at 207.194404 -92.851224)
		(property "Reference" "R685"
			(at 0 0 0)
			(layer "B.SilkS")
			(hide yes)
			(effects
				(font
					(size 1.27 1.27)
				)
				(justify mirror)
			)
		)
		(property "Value" "10R2F-L-GP"
			(at -0.064008 -3.993896 0)
			(unlocked yes)
			(layer "B.Fab")
			(hide yes)
			(effects
				(font
					(size 1.016 1.016)
					(thickness 0.1524)
				)
				(justify mirror)
			)
		)
		(property "Device Type" "R402H14"
			(at -0.064008 -5.517896 0)
			(unlocked yes)
			(layer "B.Fab")
			(hide yes)
			(effects
				(font
					(size 1.016 1.016)
					(thickness 0.1524)
				)
				(justify mirror)
			)
		)
		(duplicate_pad_numbers_are_jumpers no)
		(fp_line
			(start -0.508 -0.9398)
			(end 0.508 -0.9398)
			(stroke
				(width 0.1524)
				(type default)
			)
			(layer "B.SilkS")
		)
		(fp_line
			(start 0.508 -0.9398)
			(end 0.508 0.9398)
			(stroke
				(width 0.1524)
				(type default)
			)
			(layer "B.SilkS")
		)
		(fp_rect
			(start 0.508 0.9398)
			(end -0.508 -0.9398)
			(stroke
				(width 0)
				(type default)
			)
			(fill no)
			(layer "B.CrtYd")
		)
		(fp_rect
			(start 0.508 0.9398)
			(end -0.508 -0.9398)
			(stroke
				(width 0)
				(type default)
			)
			(fill no)
			(layer "B.Fab")
		)
		(pad "1" smd custom
			(at 0 -0.4445 180)
			(size 0.1397 0.1397)
			(layers "B.Cu" "B.Mask" "B.Paste")
			(net "P1V5")
			(options
				(clearance outline)
				(anchor circle)
			)
			(primitives
				(gr_poly
					(pts
						(arc
							(start -0.1778 0.2794)
							(mid -0.249642 0.249642)
							(end -0.2794 0.1778)
						)
						(arc
							(start -0.2794 -0.1778)
							(mid -0.249642 -0.249642)
							(end -0.1778 -0.2794)
						)
						(arc
							(start 0.1778 -0.2794)
							(mid 0.249642 -0.249642)
							(end 0.2794 -0.1778)
						)
						(arc
							(start 0.2794 0.1778)
							(mid 0.249642 0.249642)
							(end 0.1778 0.2794)
						)
					)
					(width 0)
					(fill yes)
				)
			)
		)
		(pad "2" smd custom
			(at 0 0.4445 180)
			(size 0.1397 0.1397)
			(layers "B.Cu" "B.Mask" "B.Paste")
			(net "PCE_VDDH")
			(options
				(clearance outline)
				(anchor circle)
			)
			(primitives
				(gr_poly
					(pts
						(arc
							(start -0.1778 0.2794)
							(mid -0.249642 0.249642)
							(end -0.2794 0.1778)
						)
						(arc
							(start -0.2794 -0.1778)
							(mid -0.249642 -0.249642)
							(end -0.1778 -0.2794)
						)
						(arc
							(start 0.1778 -0.2794)
							(mid 0.249642 -0.249642)
							(end 0.2794 -0.1778)
						)
						(arc
							(start 0.2794 0.1778)
							(mid 0.249642 0.249642)
							(end 0.1778 0.2794)
						)
					)
					(width 0)
					(fill yes)
				)
			)
		)
	)
	(footprint ""
		(layer "B.Cu")
		(at 168.656 -108.204 -90)
		(property "Reference" "C457"
			(at 0 0 90)
			(layer "B.SilkS")
			(hide yes)
			(effects
				(font
					(size 1.27 1.27)
				)
				(justify mirror)
			)
		)
		(property "Value" "SCD1U16V2KX-3GP"
			(at -1.1811 -2.7051 270)
			(unlocked yes)
			(layer "B.Fab")
			(hide yes)
			(effects
				(font
					(size 1.016 1.016)
					(thickness 0.1524)
				)
				(justify mirror)
			)
		)
		(property "Device Type" "C402H22"
			(at -1.1811 -4.2291 270)
			(unlocked yes)
			(layer "B.Fab")
			(hide yes)
			(effects
				(font
					(size 1.016 1.016)
					(thickness 0.1524)
				)
				(justify mirror)
			)
		)
		(duplicate_pad_numbers_are_jumpers no)
		(fp_rect
			(start 0.4318 0.9525)
			(end -0.4318 -0.9525)
			(stroke
				(width 0)
				(type default)
			)
			(fill no)
			(layer "B.CrtYd")
		)
		(fp_rect
			(start 0.4318 0.9525)
			(end -0.4318 -0.9525)
			(stroke
				(width 0)
				(type default)
			)
			(fill no)
			(layer "B.Fab")
		)
		(pad "1" smd custom
			(at 0 -0.4445 90)
			(size 0.1524 0.1524)
			(layers "B.Cu" "B.Mask" "B.Paste")
			(net "P1V8")
			(options
				(clearance outline)
				(anchor circle)
			)
			(primitives
				(gr_poly
					(pts
						(arc
							(start 0.3048 0.2032)
							(mid 0.275042 0.275042)
							(end 0.2032 0.3048)
						)
						(arc
							(start -0.2032 0.3048)
							(mid -0.275042 0.275042)
							(end -0.3048 0.2032)
						)
						(arc
							(start -0.3048 -0.2032)
							(mid -0.275042 -0.275042)
							(end -0.2032 -0.3048)
						)
						(arc
							(start 0.2032 -0.3048)
							(mid 0.275042 -0.275042)
							(end 0.3048 -0.2032)
						)
					)
					(width 0)
					(fill yes)
				)
			)
		)
		(pad "2" smd custom
			(at 0 0.4445 90)
			(size 0.1524 0.1524)
			(layers "B.Cu" "B.Mask" "B.Paste")
			(net "GND")
			(options
				(clearance outline)
				(anchor circle)
			)
			(primitives
				(gr_poly
					(pts
						(arc
							(start 0.3048 0.2032)
							(mid 0.275042 0.275042)
							(end 0.2032 0.3048)
						)
						(arc
							(start -0.2032 0.3048)
							(mid -0.275042 0.275042)
							(end -0.3048 0.2032)
						)
						(arc
							(start -0.3048 -0.2032)
							(mid -0.275042 -0.275042)
							(end -0.2032 -0.3048)
						)
						(arc
							(start 0.2032 -0.3048)
							(mid 0.275042 -0.275042)
							(end 0.3048 -0.2032)
						)
					)
					(width 0)
					(fill yes)
				)
			)
		)
	)
	(footprint ""
		(layer "B.Cu")
		(at 197.5358 -78.3336 180)
		(property "Reference" "C372"
			(at 0 0 0)
			(layer "B.SilkS")
			(hide yes)
			(effects
				(font
					(size 1.27 1.27)
				)
				(justify mirror)
			)
		)
		(property "Value" "SCD1U6D3V1KX-GP"
			(at 2.8321 -1.7399 180)
			(unlocked yes)
			(layer "B.Fab")
			(hide yes)
			(effects
				(font
					(size 1.016 1.016)
					(thickness 0.1524)
				)
				(justify mirror)
			)
		)
		(property "Device Type" "C0201H13"
			(at 2.8321 -3.2639 180)
			(unlocked yes)
			(layer "B.Fab")
			(hide yes)
			(effects
				(font
					(size 1.016 1.016)
					(thickness 0.1524)
				)
				(justify mirror)
			)
		)
		(duplicate_pad_numbers_are_jumpers no)
		(fp_rect
			(start 0.2794 0.6477)
			(end -0.2794 -0.6477)
			(stroke
				(width 0)
				(type default)
			)
			(fill no)
			(layer "B.CrtYd")
		)
		(fp_rect
			(start 0.2794 0.6477)
			(end -0.2794 -0.6477)
			(stroke
				(width 0)
				(type default)
			)
			(fill no)
			(layer "B.Fab")
		)
		(pad "1" smd custom
			(at 0 -0.2794)
			(size 0.0762 0.0762)
			(layers "B.Cu" "B.Mask" "B.Paste")
			(net "PCE_AVDD")
			(options
				(clearance outline)
				(anchor circle)
			)
			(primitives
				(gr_poly
					(pts
						(arc
							(start 0.1524 0.127)
							(mid 0.137521 0.162921)
							(end 0.1016 0.1778)
						)
						(arc
							(start -0.1016 0.1778)
							(mid -0.137521 0.162921)
							(end -0.1524 0.127)
						)
						(arc
							(start -0.1524 -0.127)
							(mid -0.137521 -0.162921)
							(end -0.1016 -0.1778)
						)
						(arc
							(start 0.1016 -0.1778)
							(mid 0.137521 -0.162921)
							(end 0.1524 -0.127)
						)
					)
					(width 0)
					(fill yes)
				)
			)
		)
		(pad "2" smd custom
			(at 0 0.2794)
			(size 0.0762 0.0762)
			(layers "B.Cu" "B.Mask" "B.Paste")
			(net "GND")
			(options
				(clearance outline)
				(anchor circle)
			)
			(primitives
				(gr_poly
					(pts
						(arc
							(start 0.1524 0.127)
							(mid 0.137521 0.162921)
							(end 0.1016 0.1778)
						)
						(arc
							(start -0.1016 0.1778)
							(mid -0.137521 0.162921)
							(end -0.1524 0.127)
						)
						(arc
							(start -0.1524 -0.127)
							(mid -0.137521 -0.162921)
							(end -0.1016 -0.1778)
						)
						(arc
							(start 0.1016 -0.1778)
							(mid 0.137521 -0.162921)
							(end 0.1524 -0.127)
						)
					)
					(width 0)
					(fill yes)
				)
			)
		)
	)
	(footprint ""
		(layer "B.Cu")
		(at 16.319754 -129.076958 180)
		(property "Reference" "R258"
			(at 0 0 0)
			(layer "B.SilkS")
			(hide yes)
			(effects
				(font
					(size 1.27 1.27)
				)
				(justify mirror)
			)
		)
		(property "Value" "120R2F-GP"
			(at -0.064008 -3.993896 180)
			(unlocked yes)
			(layer "B.Fab")
			(hide yes)
			(effects
				(font
					(size 1.016 1.016)
					(thickness 0.1524)
				)
				(justify mirror)
			)
		)
		(property "Device Type" "R402H16"
			(at -0.064008 -5.517896 180)
			(unlocked yes)
			(layer "B.Fab")
			(hide yes)
			(effects
				(font
					(size 1.016 1.016)
					(thickness 0.1524)
				)
				(justify mirror)
			)
		)
		(duplicate_pad_numbers_are_jumpers no)
		(fp_line
			(start 0.508 -0.9398)
			(end 0.508 0.9398)
			(stroke
				(width 0.1524)
				(type default)
			)
			(layer "B.SilkS")
		)
		(fp_line
			(start -0.508 -0.9398)
			(end 0.508 -0.9398)
			(stroke
				(width 0.1524)
				(type default)
			)
			(layer "B.SilkS")
		)
		(fp_rect
			(start 0.508 0.9398)
			(end -0.508 -0.9398)
			(stroke
				(width 0)
				(type default)
			)
			(fill no)
			(layer "B.CrtYd")
		)
		(fp_rect
			(start 0.508 0.9398)
			(end -0.508 -0.9398)
			(stroke
				(width 0)
				(type default)
			)
			(fill no)
			(layer "B.Fab")
		)
		(pad "1" smd custom
			(at 0 -0.4445)
			(size 0.1397 0.1397)
			(layers "B.Cu" "B.Mask" "B.Paste")
			(net "GND")
			(options
				(clearance outline)
				(anchor circle)
			)
			(primitives
				(gr_poly
					(pts
						(arc
							(start -0.1778 0.2794)
							(mid -0.249642 0.249642)
							(end -0.2794 0.1778)
						)
						(arc
							(start -0.2794 -0.1778)
							(mid -0.249642 -0.249642)
							(end -0.1778 -0.2794)
						)
						(arc
							(start 0.1778 -0.2794)
							(mid 0.249642 -0.249642)
							(end 0.2794 -0.1778)
						)
						(arc
							(start 0.2794 0.1778)
							(mid 0.249642 0.249642)
							(end 0.1778 0.2794)
						)
					)
					(width 0)
					(fill yes)
				)
			)
		)
		(pad "2" smd custom
			(at 0 0.4445)
			(size 0.1397 0.1397)
			(layers "B.Cu" "B.Mask" "B.Paste")
			(net "MEMA_12")
			(options
				(clearance outline)
				(anchor circle)
			)
			(primitives
				(gr_poly
					(pts
						(arc
							(start -0.1778 0.2794)
							(mid -0.249642 0.249642)
							(end -0.2794 0.1778)
						)
						(arc
							(start -0.2794 -0.1778)
							(mid -0.249642 -0.249642)
							(end -0.1778 -0.2794)
						)
						(arc
							(start 0.1778 -0.2794)
							(mid 0.249642 -0.249642)
							(end 0.2794 -0.1778)
						)
						(arc
							(start 0.2794 0.1778)
							(mid 0.249642 0.249642)
							(end 0.1778 0.2794)
						)
					)
					(width 0)
					(fill yes)
				)
			)
		)
	)
	(footprint ""
		(layer "B.Cu")
		(at 34.722308 -124.678694 180)
		(property "Reference" "R716"
			(at 0 0 0)
			(layer "B.SilkS")
			(hide yes)
			(effects
				(font
					(size 1.27 1.27)
				)
				(justify mirror)
			)
		)
		(property "Value" "10KR2F-2-GP"
			(at -0.064008 -3.993896 180)
			(unlocked yes)
			(layer "B.Fab")
			(hide yes)
			(effects
				(font
					(size 1.016 1.016)
					(thickness 0.1524)
				)
				(justify mirror)
			)
		)
		(property "Device Type" "R402H16"
			(at -0.064008 -5.517896 180)
			(unlocked yes)
			(layer "B.Fab")
			(hide yes)
			(effects
				(font
					(size 1.016 1.016)
					(thickness 0.1524)
				)
				(justify mirror)
			)
		)
		(duplicate_pad_numbers_are_jumpers no)
		(fp_line
			(start 0.508 -0.9398)
			(end 0.508 0.9398)
			(stroke
				(width 0.1524)
				(type default)
			)
			(layer "B.SilkS")
		)
		(fp_line
			(start -0.508 -0.9398)
			(end 0.508 -0.9398)
			(stroke
				(width 0.1524)
				(type default)
			)
			(layer "B.SilkS")
		)
		(fp_rect
			(start 0.508 0.9398)
			(end -0.508 -0.9398)
			(stroke
				(width 0)
				(type default)
			)
			(fill no)
			(layer "B.CrtYd")
		)
		(fp_rect
			(start 0.508 0.9398)
			(end -0.508 -0.9398)
			(stroke
				(width 0)
				(type default)
			)
			(fill no)
			(layer "B.Fab")
		)
		(pad "1" smd custom
			(at 0 -0.4445)
			(size 0.1397 0.1397)
			(layers "B.Cu" "B.Mask" "B.Paste")
			(net "SYS_RESET_N_OUT")
			(options
				(clearance outline)
				(anchor circle)
			)
			(primitives
				(gr_poly
					(pts
						(arc
							(start -0.1778 0.2794)
							(mid -0.249642 0.249642)
							(end -0.2794 0.1778)
						)
						(arc
							(start -0.2794 -0.1778)
							(mid -0.249642 -0.249642)
							(end -0.1778 -0.2794)
						)
						(arc
							(start 0.1778 -0.2794)
							(mid 0.249642 -0.249642)
							(end 0.2794 -0.1778)
						)
						(arc
							(start 0.2794 0.1778)
							(mid 0.249642 0.249642)
							(end 0.1778 0.2794)
						)
					)
					(width 0)
					(fill yes)
				)
			)
		)
		(pad "2" smd custom
			(at 0 0.4445)
			(size 0.1397 0.1397)
			(layers "B.Cu" "B.Mask" "B.Paste")
			(net "GND")
			(options
				(clearance outline)
				(anchor circle)
			)
			(primitives
				(gr_poly
					(pts
						(arc
							(start -0.1778 0.2794)
							(mid -0.249642 0.249642)
							(end -0.2794 0.1778)
						)
						(arc
							(start -0.2794 -0.1778)
							(mid -0.249642 -0.249642)
							(end -0.1778 -0.2794)
						)
						(arc
							(start 0.1778 -0.2794)
							(mid 0.249642 -0.249642)
							(end 0.2794 -0.1778)
						)
						(arc
							(start 0.2794 0.1778)
							(mid 0.249642 0.249642)
							(end 0.1778 0.2794)
						)
					)
					(width 0)
					(fill yes)
				)
			)
		)
	)
	(footprint ""
		(layer "B.Cu")
		(at 169.97299 -38.442138)
		(property "Reference" "C497"
			(at 0 0 0)
			(layer "B.SilkS")
			(hide yes)
			(effects
				(font
					(size 1.27 1.27)
				)
				(justify mirror)
			)
		)
		(property "Value" "SCD01U16V1KX-GP"
			(at 2.8321 -1.7399 0)
			(unlocked yes)
			(layer "B.Fab")
			(hide yes)
			(effects
				(font
					(size 1.016 1.016)
					(thickness 0.1524)
				)
				(justify mirror)
			)
		)
		(property "Device Type" "C0201H13"
			(at 2.8321 -3.2639 0)
			(unlocked yes)
			(layer "B.Fab")
			(hide yes)
			(effects
				(font
					(size 1.016 1.016)
					(thickness 0.1524)
				)
				(justify mirror)
			)
		)
		(duplicate_pad_numbers_are_jumpers no)
		(fp_rect
			(start 0.2794 0.6477)
			(end -0.2794 -0.6477)
			(stroke
				(width 0)
				(type default)
			)
			(fill no)
			(layer "B.CrtYd")
		)
		(fp_rect
			(start 0.2794 0.6477)
			(end -0.2794 -0.6477)
			(stroke
				(width 0)
				(type default)
			)
			(fill no)
			(layer "B.Fab")
		)
		(pad "1" smd custom
			(at 0 -0.2794 180)
			(size 0.0762 0.0762)
			(layers "B.Cu" "B.Mask" "B.Paste")
			(net "PHY_CON_B_TO_IOC_0_DN")
			(options
				(clearance outline)
				(anchor circle)
			)
			(primitives
				(gr_poly
					(pts
						(arc
							(start 0.1524 0.127)
							(mid 0.137521 0.162921)
							(end 0.1016 0.1778)
						)
						(arc
							(start -0.1016 0.1778)
							(mid -0.137521 0.162921)
							(end -0.1524 0.127)
						)
						(arc
							(start -0.1524 -0.127)
							(mid -0.137521 -0.162921)
							(end -0.1016 -0.1778)
						)
						(arc
							(start 0.1016 -0.1778)
							(mid 0.137521 -0.162921)
							(end 0.1524 -0.127)
						)
					)
					(width 0)
					(fill yes)
				)
			)
		)
		(pad "2" smd custom
			(at 0 0.2794 180)
			(size 0.0762 0.0762)
			(layers "B.Cu" "B.Mask" "B.Paste")
			(net "PHY_CON_B_TO_IOC_0_DN_C")
			(options
				(clearance outline)
				(anchor circle)
			)
			(primitives
				(gr_poly
					(pts
						(arc
							(start 0.1524 0.127)
							(mid 0.137521 0.162921)
							(end 0.1016 0.1778)
						)
						(arc
							(start -0.1016 0.1778)
							(mid -0.137521 0.162921)
							(end -0.1524 0.127)
						)
						(arc
							(start -0.1524 -0.127)
							(mid -0.137521 -0.162921)
							(end -0.1016 -0.1778)
						)
						(arc
							(start 0.1016 -0.1778)
							(mid 0.137521 -0.162921)
							(end 0.1524 -0.127)
						)
					)
					(width 0)
					(fill yes)
				)
			)
		)
	)
)
